# BASEBOARD_FAB2 (Tioga Pass) — schematic netlist excerpt (pin names and nets, part order shuffled) for the footprints in the layout excerpt that follows; sources: Cadence DE-HDL packaged netlist, KiCad conversion of Wiwynn_Tioga_Pass_MB.brd

C4D13  CAP  0.22UF 16V 10% X7R  pkg 0402  page 203 : A = P5V_STBY ; B = GND
R7F5  RES  4.75K 1% CHIP  pkg 0402  page 153 : A = P3V3_STBY ; B = SPI_CS0_PRIMARY_R_N

(kicad_pcb
	(version 20260206)
	(generator "pcbnew")
	(generator_version "10.0")
	(general
		(thickness 1.6)
		(legacy_teardrops no)
	)
	(paper "A4")
	(title_block
		(title "Wiwynn_Tioga_Pass_MB.brd")
		(comment 1 "Tioga Pass / footprints 2200-2201 of 4770")
	)
	(layers
		(0 "F.Cu" signal "TOP")
		(4 "In1.Cu" signal "L2GND")
		(6 "In2.Cu" signal "L3")
		(8 "In3.Cu" signal "L4GND")
		(10 "In4.Cu" signal "L5")
		(12 "In5.Cu" signal "L6GND")
		(14 "In6.Cu" signal "L7VCC")
		(16 "In7.Cu" signal "L8VCC")
		(18 "In8.Cu" signal "L9GND")
		(20 "In9.Cu" signal "L10")
		(22 "In10.Cu" signal "L11GND")
		(24 "In11.Cu" signal "L12")
		(26 "In12.Cu" signal "L13GND")
		(2 "B.Cu" signal "BOTTOM")
		(9 "F.Adhes" user "F.Adhesive")
		(11 "B.Adhes" user "B.Adhesive")
		(13 "F.Paste" user "Package Geometry/Pastemask Top")
		(15 "B.Paste" user "Package Geometry/Pastemask Bottom")
		(5 "F.SilkS" user "Ref Des/Silkscreen Top")
		(7 "B.SilkS" user "Ref Des/Silkscreen Bottom")
		(1 "F.Mask" user "Board Geometry/Soldermask Top")
		(3 "B.Mask" user "Board Geometry/Soldermask Bottom")
		(17 "Dwgs.User" user "User.Drawings")
		(19 "Cmts.User" user "User.Comments")
		(21 "Eco1.User" user "User.Eco1")
		(23 "Eco2.User" user "User.Eco2")
		(25 "Edge.Cuts" user "Board Geometry/Outline")
		(27 "Margin" user)
		(31 "F.CrtYd" user "Package Geometry/Place Bound Top")
		(29 "B.CrtYd" user "Package Geometry/Place Bound Bottom")
		(35 "F.Fab" user "Ref Des/Assembly Top")
		(33 "B.Fab" user "Ref Des/Assembly Bottom")
	)
	(footprint ""
		(layer "F.Cu")
		(at 401.7518 -53.53558 -90)
		(property "Reference" "R7F5"
			(at 0 0 270)
			(layer "F.SilkS")
			(hide yes)
			(effects
				(font
					(size 1.27 1.27)
				)
			)
		)
		(property "Value" ""
			(at 0 0 270)
			(layer "F.Fab")
			(effects
				(font
					(size 1.27 1.27)
				)
			)
		)
		(duplicate_pad_numbers_are_jumpers no)
		(fp_poly
			(pts
				(xy -0.2794 -0.1016) (xy 0.2794 -0.1016) (xy 0.2794 0.9906) (xy -0.2794 0.9906)
			)
			(stroke
				(width 0)
				(type default)
			)
			(fill no)
			(layer "F.CrtYd")
		)
		(fp_line
			(start -0.2794 0.9906)
			(end 0.2794 0.9906)
			(stroke
				(width 0.1)
				(type default)
			)
			(layer "F.Fab")
		)
		(fp_line
			(start 0.2794 0.9906)
			(end 0.2794 -0.1016)
			(stroke
				(width 0.1)
				(type default)
			)
			(layer "F.Fab")
		)
		(fp_line
			(start -0.2794 -0.1016)
			(end -0.2794 0.9906)
			(stroke
				(width 0.1)
				(type default)
			)
			(layer "F.Fab")
		)
		(fp_line
			(start 0.2794 -0.1016)
			(end -0.2794 -0.1016)
			(stroke
				(width 0.1)
				(type default)
			)
			(layer "F.Fab")
		)
		(pad "1" smd rect
			(at 0 0 270)
			(size 0.508 0.508)
			(layers "F.Cu" "F.Mask" "F.Paste")
			(net "P3V3_STBY")
		)
		(pad "2" smd rect
			(at 0 0.889 270)
			(size 0.508 0.508)
			(layers "F.Cu" "F.Mask" "F.Paste")
			(net "SPI_CS0_PRIMARY_R_N")
		)
		(zone
			(layer "F.Cu")
			(hatch none 0.5)
			(connect_pads
				(clearance 0)
			)
			(min_thickness 0.25)
			(keepout
				(tracks not_allowed)
				(vias allowed)
				(pads allowed)
				(copperpour not_allowed)
				(footprints allowed)
			)
			(placement
				(enabled no)
				(sheetname "")
			)
			(fill
				(thermal_gap 0.5)
				(thermal_bridge_width 0.5)
				(island_removal_mode 0)
			)
			(polygon
				(pts
					(xy 401.1168 -53.78958) (xy 401.1168 -53.28158) (xy 401.4978 -53.28158) (xy 401.4978 -53.78958)
				)
			)
		)
		(zone
			(layer "F.Cu")
			(hatch none 0.5)
			(connect_pads
				(clearance 0)
			)
			(min_thickness 0.25)
			(keepout
				(tracks allowed)
				(vias not_allowed)
				(pads allowed)
				(copperpour not_allowed)
				(footprints allowed)
			)
			(placement
				(enabled no)
				(sheetname "")
			)
			(fill
				(thermal_gap 0.5)
				(thermal_bridge_width 0.5)
				(island_removal_mode 0)
			)
			(polygon
				(pts
					(xy 401.4978 -53.78958) (xy 401.4978 -53.28158) (xy 401.1168 -53.28158) (xy 401.1168 -53.78958)
				)
			)
		)
	)
	(footprint ""
		(layer "F.Cu")
		(at 198.00443 -69.318124 90)
		(property "Reference" "C4D13"
			(at -0.8382 -0.67818 90)
			(unlocked yes)
			(layer "F.SilkS")
			(effects
				(font
					(size 0.4064 0.254)
					(thickness 0.1524)
				)
				(justify left)
			)
		)
		(property "Value" ""
			(at 0 0 90)
			(layer "F.Fab")
			(effects
				(font
					(size 1.27 1.27)
				)
			)
		)
		(duplicate_pad_numbers_are_jumpers no)
		(fp_poly
			(pts
				(xy 0.3048 -0.1016) (xy 0.3048 0.9906) (xy -0.3048 0.9906) (xy -0.3048 -0.1016)
			)
			(stroke
				(width 0)
				(type default)
			)
			(fill no)
			(layer "F.CrtYd")
		)
		(fp_line
			(start 0.3048 -0.1016)
			(end -0.3048 -0.1016)
			(stroke
				(width 0.1)
				(type default)
			)
			(layer "F.Fab")
		)
		(fp_line
			(start -0.3048 -0.1016)
			(end -0.3048 0.9906)
			(stroke
				(width 0.1)
				(type default)
			)
			(layer "F.Fab")
		)
		(fp_line
			(start 0.3048 0.9906)
			(end 0.3048 -0.1016)
			(stroke
				(width 0.1)
				(type default)
			)
			(layer "F.Fab")
		)
		(fp_line
			(start -0.3048 0.9906)
			(end 0.3048 0.9906)
			(stroke
				(width 0.1)
				(type default)
			)
			(layer "F.Fab")
		)
		(pad "1" smd rect
			(at 0 0 90)
			(size 0.508 0.508)
			(layers "F.Cu" "F.Mask" "F.Paste")
			(net "P5V_STBY")
		)
		(pad "2" smd rect
			(at 0 0.889 90)
			(size 0.508 0.508)
			(layers "F.Cu" "F.Mask" "F.Paste")
			(net "GND")
		)
		(zone
			(layer "F.Cu")
			(hatch none 0.5)
			(connect_pads
				(clearance 0)
			)
			(min_thickness 0.25)
			(keepout
				(tracks allowed)
				(vias not_allowed)
				(pads allowed)
				(copperpour not_allowed)
				(footprints allowed)
			)
			(placement
				(enabled no)
				(sheetname "")
			)
			(fill
				(thermal_gap 0.5)
				(thermal_bridge_width 0.5)
				(island_removal_mode 0)
			)
			(polygon
				(pts
					(xy 198.25843 -69.064124) (xy 198.25843 -69.572124) (xy 198.63943 -69.572124) (xy 198.63943 -69.064124)
				)
			)
		)
		(zone
			(layer "F.Cu")
			(hatch none 0.5)
			(connect_pads
				(clearance 0)
			)
			(min_thickness 0.25)
			(keepout
				(tracks not_allowed)
				(vias allowed)
				(pads allowed)
				(copperpour not_allowed)
				(footprints allowed)
			)
			(placement
				(enabled no)
				(sheetname "")
			)
			(fill
				(thermal_gap 0.5)
				(thermal_bridge_width 0.5)
				(island_removal_mode 0)
			)
			(polygon
				(pts
					(xy 198.63943 -69.064124) (xy 198.63943 -69.572124) (xy 198.25843 -69.572124) (xy 198.25843 -69.064124)
				)
			)
		)
	)
)
